FILE_TYPE = CONNECTIVITY;
{Allegro Design Entry HDL 17.2-2016 S081 (4005846) 1/11/2022}
"PAGE_NUMBER" = 241;
0"NC";
1"P3V3_AUX\g";
2"P3V3_AUX\g";
3"P3V3_AUX\g";
4"P12V_AUX\g";
5"P12V_PSU\g";
6"P3V3_AUX\g";
7"P3V3_AUX\g";
8"P3V3_AUX\g";
9"GND\g";
10"GND\g";
11"GND\g";
12"GND\g";
13"GND\g";
14"GND\g";
15"GND\g";
16"GND\g";
17"LED_P12V_SCM_FAULT_D2";
18"LED_P12V_PSU_R1"CDS_PHYS_NET_NAME"P12V_AUX_CPU0_DIMM_ISEN_P";
19"P12V_SCM_FAULT_R_N"VOLTAGE"0";
20"LED_P12V_SCM_FAULT_D1";
21"LED_P12V_AUX_R3"CDS_PHYS_NET_NAME"P12V_AUX_CPU0_DIMM_ISEN_P";
22"LED_P12V_PSU_R3"CDS_PHYS_NET_NAME"P12V_AUX_CPU0_DIMM_ISEN_P";
23"LED_P12V_AUX_R2"CDS_PHYS_NET_NAME"P12V_AUX_CPU0_DIMM_ISEN_P";
24"LED_P12V_SCM_FAULT";
25"LED_PWRGD_PCH_PWROK_R";
26"LED_RST_PLTRST_N";
27"PWRGD_CPUPWRGD_LVC2_R1";
28"LED_PWRGD_CPUPWRGD_GTL";
29"LED_RST_PLTRST_N_D";
30"LED_P12V_PSU_R2"CDS_PHYS_NET_NAME"P12V_AUX_CPU0_DIMM_ISEN_P";
31"LED_P12V_AUX_R1"CDS_PHYS_NET_NAME"P12V_AUX_CPU0_DIMM_ISEN_P";
32"LED_PWRGD_SYS_PWROK_R";
33"LED_PWRGD_PCH_PWROK_R_D";
34"RST_PLTRST_N";
35"PWRGD_SYS_PWROK_R";
36"PWRGD_PCH_PWROK_R";
37"LED_PWRGD_SYS_PWROK_R_D";
38"LED_PWRGD_CPUPWRGD_GTL_D";
%"UNIVERSAL_GND"
"1","(-13450,1450)","0","logical_power","I10";
;
CDS_LIB"logical_power"
HDL_POWER"GND";
"A"12;
%"Q_LED"
"1","(-12375,700)","2","pure_quanta","I11";
;
PART_NUMBER"BEBL0172Z00"
MATERIAL"IC"
MANUF_PN"LTST-C281TBKT-5A"
PACK_TYPE"SMLF"
LOCATION"D89"
COLOR"LED_BLUE"
CDS_LIB"pure_quanta"
NEEDS_NO_SIZE"TRUE"
$SEC"1"
CDS_SEC"1";
"A"
$PN"A"28;
"C"
$PN"C"38;
%"UNIVERSAL_POWER"
"1","(-10450,875)","0","logical_power","I15";
;
HDL_POWER"P3V3_AUX"
CDS_LIB"logical_power";
"A"6;
%"MOSFET_NCH_DUAL"
"2","(-13500,1800)","0","pure_quanta","I16";
;
PART_NUMBER"BAM138K0003"
VALUE"PJT138K"
PART_TYPE"SMLF"
MATERIAL"IC"
LOCATION"Q87"
CDS_LMAN_SYM_OUTLINE"-150,150,150,-150"
CDS_LIB"pure_quanta"
SEC_TYPE""
NEEDS_NO_SIZE"TRUE"
SEC"2";
"S2"
$PN"4"12;
"G2"
$PN"5"35;
"D2"
$PN"3"37;
%"MOSFET_NCH_DUAL"
"1","(-13500,3075)","0","pure_quanta","I17";
;
PART_NUMBER"BAM138K0003"
PART_TYPE"SMLF"
VALUE"PJT138K"
MATERIAL"IC"
LOCATION"Q87"
CDS_LMAN_SYM_OUTLINE"-150,150,150,-150"
CDS_LIB"pure_quanta"
NEEDS_NO_SIZE"TRUE"
$SEC"1"
CDS_SEC"1";
"D1"
$PN"6"33;
"G1"
$PN"2"36;
"S1"
$PN"1"11;
%"UNIVERSAL_GND"
"1","(-13450,2725)","0","logical_power","I18";
;
CDS_LIB"logical_power"
HDL_POWER"GND";
"A"11;
%"Q_LED"
"1","(-12425,2075)","2","pure_quanta","I19";
;
PART_NUMBER"BEBL0172Z00"
MANUF_PN"LTST-C281TBKT-5A"
COLOR"LED_BLUE"
PACK_TYPE"SMLF"
MATERIAL"IC"
LOCATION"D88"
CDS_LIB"pure_quanta"
NEEDS_NO_SIZE"TRUE"
$SEC"1"
CDS_SEC"1";
"A"
$PN"A"32;
"C"
$PN"C"37;
%"Q_LED"
"1","(-12425,3350)","2","pure_quanta","I20";
;
PART_NUMBER"BEBL0172Z00"
MANUF_PN"LTST-C281TBKT-5A"
COLOR"LED_BLUE"
MATERIAL"IC"
PACK_TYPE"SMLF"
LOCATION"D87"
NEEDS_NO_SIZE"TRUE"
CDS_LIB"pure_quanta"
$SEC"1"
CDS_SEC"1";
"A"
$PN"A"25;
"C"
$PN"C"33;
%"UNIVERSAL_POWER"
"1","(-10475,2275)","0","logical_power","I24";
;
HDL_POWER"P3V3_AUX"
CDS_LIB"logical_power";
"A"3;
%"UNIVERSAL_POWER"
"1","(-10425,3650)","0","logical_power","I25";
;
HDL_POWER"P3V3_AUX"
CDS_LIB"logical_power";
"A"2;
%"UNIVERSAL_GND"
"1","(-13375,-1375)","0","logical_power","I31";
;
HDL_POWER"GND"
CDS_LIB"logical_power";
"A"13;
%"Q_LED"
"1","(-12350,-750)","2","pure_quanta","I33";
;
PART_NUMBER"BEBL0172Z00"
MATERIAL"IC"
PACK_TYPE"SMLF"
MANUF_PN"LTST-C281TBKT-5A"
COLOR"LED_BLUE"
LOCATION"D90"
CDS_LIB"pure_quanta"
NEEDS_NO_SIZE"TRUE"
$SEC"1"
CDS_SEC"1";
"A"
$PN"A"26;
"C"
$PN"C"29;
%"UNIVERSAL_POWER"
"1","(-10325,-575)","0","logical_power","I37";
;
HDL_POWER"P3V3_AUX"
CDS_LIB"logical_power";
"A"8;
%"Q_RES"
"1","(-11125,3350)","0","pure_quanta","I38";
;
PART_NUMBER"CS11302FB03"
PACK_TYPE"0402LF"
TOLERANCE"1%"
VALUE"130"
WATTAGE"1/16W"
MATERIAL"CHIP"
$LOCATION"R3068"
CDS_LIB"pure_quanta"
CDS_LOCATION"R3068"
$SEC"1"
CDS_SEC"1";
"B"
$PN"2"2;
"A"
$PN"1"25;
%"Q_RES"
"1","(-11125,2075)","0","pure_quanta","I39";
;
PART_NUMBER"CS11302FB03"
MATERIAL"CHIP"
WATTAGE"1/16W"
TOLERANCE"1%"
VALUE"130"
PACK_TYPE"0402LF"
$LOCATION"R3069"
CDS_LIB"pure_quanta"
CDS_LOCATION"R3069"
$SEC"1"
CDS_SEC"1";
"B"
$PN"2"3;
"A"
$PN"1"32;
%"Q_RES"
"1","(-11075,700)","0","pure_quanta","I40";
;
PART_NUMBER"CS11302FB03"
VALUE"130"
MATERIAL"CHIP"
PACK_TYPE"0402LF"
WATTAGE"1/16W"
TOLERANCE"1%"
$LOCATION"R1044"
CDS_LIB"pure_quanta"
CDS_LOCATION"R1044"
$SEC"1"
CDS_SEC"1";
"B"
$PN"2"6;
"A"
$PN"1"28;
%"Q_RES"
"1","(-10950,-750)","0","pure_quanta","I41";
;
PART_NUMBER"CS11302FB03"
VALUE"130"
TOLERANCE"1%"
MATERIAL"CHIP"
WATTAGE"1/16W"
PACK_TYPE"0402LF"
$LOCATION"R3070"
CDS_LIB"pure_quanta"
CDS_LOCATION"R3070"
$SEC"1"
CDS_SEC"1";
"B"
$PN"2"8;
"A"
$PN"1"26;
%"MOSFET_NCH_DUAL"
"2","(-13425,-1025)","0","pure_quanta","I42";
;
PART_NUMBER"BAM138K0003"
PART_TYPE"SMLF"
MATERIAL"IC"
VALUE"PJT138K"
LOCATION"Q88"
CDS_LIB"pure_quanta"
CDS_LMAN_SYM_OUTLINE"-150,150,150,-150"
NEEDS_NO_SIZE"TRUE"
$SEC"2"
CDS_SEC"2";
"S2"
$PN"4"13;
"G2"
$PN"5"34;
"D2"
$PN"3"29;
%"UNIVERSAL_POWER"
"1","(-6325,2475)","0","logical_power","I47";
;
HDL_POWER"P12V_PSU"
CDS_LIB"logical_power";
"A"5;
%"Q_LED"
"1","(-9125,2150)","2","pure_quanta","I49";
;
PART_NUMBER"BEBL0172Z00"
MANUF_PN"LTST-C281TBKT-5A"
MATERIAL"IC"
PACK_TYPE"SMLF"
COLOR"LED_BLUE"
$LOCATION"D143"
CDS_LIB"pure_quanta"
NEEDS_NO_SIZE"TRUE"
CDS_LOCATION"D143"
$SEC"1"
CDS_SEC"1";
"A"
$PN"A"18;
"C"
$PN"C"15;
%"UNIVERSAL_GND"
"1","(-9400,1875)","0","logical_power","I50";
;
HDL_POWER"GND"
CDS_LIB"logical_power";
"A"15;
%"UNIVERSAL_POWER"
"1","(-6325,3725)","0","logical_power","I54";
;
HDL_POWER"P12V_AUX"
CDS_LIB"logical_power";
"A"4;
%"Q_LED"
"1","(-9125,3400)","2","pure_quanta","I58";
;
PART_NUMBER"BEBL0172Z00"
COLOR"LED_BLUE"
PACK_TYPE"SMLF"
MATERIAL"IC"
MANUF_PN"LTST-C281TBKT-5A"
$LOCATION"D142"
NEEDS_NO_SIZE"TRUE"
CDS_LIB"pure_quanta"
CDS_LOCATION"D142"
$SEC"1"
CDS_SEC"1";
"A"
$PN"A"31;
"C"
$PN"C"14;
%"UNIVERSAL_GND"
"1","(-9400,3125)","0","logical_power","I59";
;
CDS_LIB"logical_power"
HDL_POWER"GND";
"A"14;
%"Q_RES"
"1","(-8400,2150)","0","pure_quanta","I61";
;
PART_NUMBER"CS15602FB03"
WATTAGE"1/16W"
MATERIAL"CHIP"
VALUE"560"
TOLERANCE"1%"
PACK_TYPE"0402LF"
$LOCATION"R4703"
CDS_LIB"pure_quanta"
CDS_LOCATION"R4703"
$SEC"1"
CDS_SEC"1";
"B"
$PN"2"30;
"A"
$PN"1"18;
%"Q_RES"
"1","(-7700,2150)","0","pure_quanta","I62";
;
PART_NUMBER"CS15602FB03"
TOLERANCE"1%"
VALUE"560"
WATTAGE"1/16W"
PACK_TYPE"0402LF"
MATERIAL"CHIP"
$LOCATION"R4705"
CDS_LIB"pure_quanta"
CDS_LOCATION"R4705"
$SEC"1"
CDS_SEC"1";
"B"
$PN"2"22;
"A"
$PN"1"30;
%"Q_RES"
"1","(-6825,2150)","0","pure_quanta","I63";
;
PART_NUMBER"CS15602FB03"
VALUE"560"
WATTAGE"1/16W"
MATERIAL"CHIP"
TOLERANCE"1%"
PACK_TYPE"0402LF"
$LOCATION"R4707"
CDS_LIB"pure_quanta"
CDS_LOCATION"R4707"
$SEC"1"
CDS_SEC"1";
"B"
$PN"2"5;
"A"
$PN"1"22;
%"Q_RES"
"1","(-8400,3400)","0","pure_quanta","I64";
;
PART_NUMBER"CS15602FB03"
PACK_TYPE"0402LF"
MATERIAL"CHIP"
TOLERANCE"1%"
WATTAGE"1/16W"
VALUE"560"
$LOCATION"R4702"
CDS_LIB"pure_quanta"
CDS_LOCATION"R4702"
$SEC"1"
CDS_SEC"1";
"B"
$PN"2"23;
"A"
$PN"1"31;
%"Q_RES"
"1","(-7725,3400)","0","pure_quanta","I65";
;
PART_NUMBER"CS15602FB03"
VALUE"560"
WATTAGE"1/16W"
MATERIAL"CHIP"
PACK_TYPE"0402LF"
TOLERANCE"1%"
$LOCATION"R4704"
CDS_LIB"pure_quanta"
CDS_LOCATION"R4704"
$SEC"1"
CDS_SEC"1";
"B"
$PN"2"21;
"A"
$PN"1"23;
%"Q_RES"
"1","(-6825,3400)","0","pure_quanta","I66";
;
PART_NUMBER"CS15602FB03"
WATTAGE"1/16W"
PACK_TYPE"0402LF"
TOLERANCE"1%"
VALUE"560"
MATERIAL"CHIP"
$LOCATION"R4706"
CDS_LIB"pure_quanta"
CDS_LOCATION"R4706"
$SEC"1"
CDS_SEC"1";
"B"
$PN"2"4;
"A"
$PN"1"21;
%"Q_LED"
"1","(-7500,425)","2","pure_quanta","I67";
;
PART_NUMBER"BEYL0159Z00"
MATERIAL"IC"
COLOR"LED_YELLOW"
PACK_TYPE"SMLF"
MANUF_PN"LTST-C190KSKT-P"
$LOCATION"D144"
CDS_LIB"pure_quanta"
NEEDS_NO_SIZE"TRUE"
CDS_LOCATION"D144"
$SEC"1"
CDS_SEC"1";
"A"
$PN"A"24;
"C"
$PN"C"17;
%"Q_RES"
"1","(-6525,425)","0","pure_quanta","I68";
;
PART_NUMBER"CS12492FB02"
VALUE"249"
WATTAGE"1/16W"
PACK_TYPE"0402LF"
TOLERANCE"1%"
MATERIAL"CHIP"
$LOCATION"R4711"
CDS_LIB"pure_quanta"
CDS_LOCATION"R4711"
$SEC"1"
CDS_SEC"1";
"B"
$PN"2"1;
"A"
$PN"1"24;
%"MOSFET_NCH_DUAL"
"1","(-9075,-225)","0","pure_quanta","I69";
;
PART_NUMBER"BAM138K0003"
MATERIAL"IC"
PART_TYPE"SMLF"
VALUE"PJT138K"
$LOCATION"Q150"
CDS_LIB"pure_quanta"
CDS_LMAN_SYM_OUTLINE"-150,150,150,-150"
NEEDS_NO_SIZE"TRUE"
CDS_LOCATION"Q150"
$SEC"1"
CDS_SEC"1";
"D1"
$PN"6"20;
"G1"
$PN"2"19;
"S1"
$PN"1"9;
%"UNIVERSAL_POWER"
"1","(-6150,725)","0","logical_power","I71";
;
HDL_POWER"P3V3_AUX"
CDS_LIB"logical_power";
"A"1;
%"MOSFET_NCH_DUAL"
"2","(-8025,150)","0","pure_quanta","I72";
;
PART_NUMBER"BAM138K0003"
PART_TYPE"SMLF"
MATERIAL"IC"
VALUE"PJT138K"
$LOCATION"Q150"
CDS_LIB"pure_quanta"
CDS_LMAN_SYM_OUTLINE"-150,150,150,-150"
NEEDS_NO_SIZE"TRUE"
CDS_LOCATION"Q150"
$SEC"2"
CDS_SEC"2";
"S2"
$PN"4"16;
"G2"
$PN"5"20;
"D2"
$PN"3"17;
%"UNIVERSAL_GND"
"1","(-7975,-300)","0","logical_power","I73";
;
CDS_LIB"logical_power"
HDL_POWER"GND";
"A"16;
%"Q_RES"
"2","(-9025,425)","0","pure_quanta","I74";
;
PART_NUMBER"CS24702JB10"
WATTAGE"1/16W"
PACK_TYPE"0402LF"
MATERIAL"CHIP"
VALUE"4.7K"
TOLERANCE"5%"
$LOCATION"R4710"
CDS_LIB"pure_quanta"
CDS_LOCATION"R4710"
$SEC"1"
CDS_SEC"1";
"A"
$PN"1"7;
"B"
$PN"2"20;
%"UNIVERSAL_POWER"
"1","(-9025,725)","0","logical_power","I75";
;
HDL_POWER"P3V3_AUX"
CDS_LIB"logical_power";
"A"7;
%"UNIVERSAL_GND"
"1","(-9025,-675)","0","logical_power","I76";
;
HDL_POWER"GND"
CDS_LIB"logical_power";
"A"9;
%"MOSFET_NCH_DUAL"
"1","(-13450,425)","0","pure_quanta","I8";
;
PART_NUMBER"BAM138K0003"
PART_TYPE"SMLF"
VALUE"PJT138K"
MATERIAL"IC"
LOCATION"Q88"
CDS_LMAN_SYM_OUTLINE"-150,150,150,-150"
CDS_LIB"pure_quanta"
NEEDS_NO_SIZE"TRUE"
$SEC"1"
CDS_SEC"1";
"D1"
$PN"6"38;
"G1"
$PN"2"27;
"S1"
$PN"1"10;
%"UNIVERSAL_GND"
"1","(-13400,75)","0","logical_power","I9";
;
CDS_LIB"logical_power"
HDL_POWER"GND";
"A"10;
END.
